# BASEBOARD_FAB2 (Tioga Pass) — schematic netlist excerpt (pin names and nets, part order shuffled) for the footprints in the layout excerpt that follows; sources: Cadence DE-HDL packaged netlist, KiCad conversion of Wiwynn_Tioga_Pass_MB.brd

C3P14  CAP  0.22UF 16V 10% X7R  pkg 0402  page 107 : A = P3E_CPU0_PE1_SS_TXP<1> ; B = P3E_CPU0_PE1_SS_C_TXP<1>
C3M20  CAP_A  1.0UF 6.3V 10% X6S  pkg 0402V  page 127 : A = P1V05_PCH_STBY_VCCA_PLL0 ; B = GND
C8M3  CAP_A  47UF 4V 20% X5R  pkg 0603V  page 228 : A = PVDDQ_KLM ; B = GND

(kicad_pcb
	(version 20260206)
	(generator "pcbnew")
	(generator_version "10.0")
	(general
		(thickness 1.6)
		(legacy_teardrops no)
	)
	(paper "A4")
	(title_block
		(title "Wiwynn_Tioga_Pass_MB.brd")
		(comment 1 "Tioga Pass / footprints 3742-3744 of 4770")
	)
	(layers
		(0 "F.Cu" signal "TOP")
		(4 "In1.Cu" signal "L2GND")
		(6 "In2.Cu" signal "L3")
		(8 "In3.Cu" signal "L4GND")
		(10 "In4.Cu" signal "L5")
		(12 "In5.Cu" signal "L6GND")
		(14 "In6.Cu" signal "L7VCC")
		(16 "In7.Cu" signal "L8VCC")
		(18 "In8.Cu" signal "L9GND")
		(20 "In9.Cu" signal "L10")
		(22 "In10.Cu" signal "L11GND")
		(24 "In11.Cu" signal "L12")
		(26 "In12.Cu" signal "L13GND")
		(2 "B.Cu" signal "BOTTOM")
		(9 "F.Adhes" user "F.Adhesive")
		(11 "B.Adhes" user "B.Adhesive")
		(13 "F.Paste" user "Package Geometry/Pastemask Top")
		(15 "B.Paste" user "Package Geometry/Pastemask Bottom")
		(5 "F.SilkS" user "Ref Des/Silkscreen Top")
		(7 "B.SilkS" user "Ref Des/Silkscreen Bottom")
		(1 "F.Mask" user "Board Geometry/Soldermask Top")
		(3 "B.Mask" user "Board Geometry/Soldermask Bottom")
		(17 "Dwgs.User" user "User.Drawings")
		(19 "Cmts.User" user "User.Comments")
		(21 "Eco1.User" user "User.Eco1")
		(23 "Eco2.User" user "User.Eco2")
		(25 "Edge.Cuts" user "Board Geometry/Outline")
		(27 "Margin" user)
		(31 "F.CrtYd" user "Package Geometry/Place Bound Top")
		(29 "B.CrtYd" user "Package Geometry/Place Bound Bottom")
		(35 "F.Fab" user "Ref Des/Assembly Top")
		(33 "B.Fab" user "Ref Des/Assembly Bottom")
	)
	(footprint ""
		(layer "B.Cu")
		(at 88.392 -135.4074 90)
		(property "Reference" "C8M3"
			(at -1.848866 0.752348 90)
			(unlocked yes)
			(layer "B.SilkS")
			(effects
				(font
					(size 1.27 0.9652)
					(thickness 0.1524)
				)
				(justify mirror)
			)
		)
		(property "Value" ""
			(at 0 0 90)
			(layer "B.Fab")
			(effects
				(font
					(size 1.27 1.27)
				)
				(justify mirror)
			)
		)
		(duplicate_pad_numbers_are_jumpers no)
		(fp_rect
			(start 0.500126 1.598422)
			(end -0.500126 -0.201422)
			(stroke
				(width 0)
				(type default)
			)
			(fill no)
			(layer "B.CrtYd")
		)
		(fp_line
			(start 0.500126 -0.201422)
			(end -0.500126 -0.201422)
			(stroke
				(width 0.1)
				(type default)
			)
			(layer "B.Fab")
		)
		(fp_line
			(start -0.500126 -0.201422)
			(end -0.500126 1.598422)
			(stroke
				(width 0.1)
				(type default)
			)
			(layer "B.Fab")
		)
		(fp_line
			(start 0.500126 1.598422)
			(end 0.500126 -0.201422)
			(stroke
				(width 0.1)
				(type default)
			)
			(layer "B.Fab")
		)
		(fp_line
			(start -0.500126 1.598422)
			(end 0.500126 1.598422)
			(stroke
				(width 0.1)
				(type default)
			)
			(layer "B.Fab")
		)
		(pad "1" smd rect
			(at 0 0)
			(size 0.889 0.9906)
			(layers "B.Cu" "B.Mask" "B.Paste")
			(net "PVDDQ_KLM")
		)
		(pad "2" smd rect
			(at 0 1.397)
			(size 0.889 0.9906)
			(layers "B.Cu" "B.Mask" "B.Paste")
			(net "GND")
		)
		(zone
			(layer "B.Cu")
			(hatch none 0.5)
			(connect_pads
				(clearance 0)
			)
			(min_thickness 0.25)
			(keepout
				(tracks not_allowed)
				(vias allowed)
				(pads allowed)
				(copperpour not_allowed)
				(footprints allowed)
			)
			(placement
				(enabled no)
				(sheetname "")
			)
			(fill
				(thermal_gap 0.5)
				(thermal_bridge_width 0.5)
				(island_removal_mode 0)
			)
			(polygon
				(pts
					(xy 89.3445 -135.9027) (xy 88.8365 -135.9027) (xy 88.8365 -134.9121) (xy 89.3445 -134.9121)
				)
			)
		)
		(zone
			(layer "B.Cu")
			(hatch none 0.5)
			(connect_pads
				(clearance 0)
			)
			(min_thickness 0.25)
			(keepout
				(tracks allowed)
				(vias not_allowed)
				(pads allowed)
				(copperpour not_allowed)
				(footprints allowed)
			)
			(placement
				(enabled no)
				(sheetname "")
			)
			(fill
				(thermal_gap 0.5)
				(thermal_bridge_width 0.5)
				(island_removal_mode 0)
			)
			(polygon
				(pts
					(xy 89.3445 -135.9027) (xy 88.8365 -135.9027) (xy 88.8365 -134.9121) (xy 89.3445 -134.9121)
				)
			)
		)
	)
	(footprint ""
		(layer "B.Cu")
		(at 375.412 -134.8105)
		(property "Reference" "C3M20"
			(at 0 0 0)
			(layer "B.SilkS")
			(hide yes)
			(effects
				(font
					(size 1.27 1.27)
				)
				(justify mirror)
			)
		)
		(property "Value" ""
			(at 0 0 0)
			(layer "B.Fab")
			(effects
				(font
					(size 1.27 1.27)
				)
				(justify mirror)
			)
		)
		(duplicate_pad_numbers_are_jumpers no)
		(fp_poly
			(pts
				(xy -0.3048 -0.1016) (xy -0.3048 0.9906) (xy 0.3048 0.9906) (xy 0.3048 -0.1016)
			)
			(stroke
				(width 0)
				(type default)
			)
			(fill no)
			(layer "B.CrtYd")
		)
		(fp_line
			(start -0.3048 -0.1016)
			(end 0.3048 -0.1016)
			(stroke
				(width 0.1)
				(type default)
			)
			(layer "B.Fab")
		)
		(fp_line
			(start -0.3048 0.9906)
			(end -0.3048 -0.1016)
			(stroke
				(width 0.1)
				(type default)
			)
			(layer "B.Fab")
		)
		(fp_line
			(start 0.3048 -0.1016)
			(end 0.3048 0.9906)
			(stroke
				(width 0.1)
				(type default)
			)
			(layer "B.Fab")
		)
		(fp_line
			(start 0.3048 0.9906)
			(end -0.3048 0.9906)
			(stroke
				(width 0.1)
				(type default)
			)
			(layer "B.Fab")
		)
		(pad "1" smd rect
			(at 0 0 180)
			(size 0.508 0.508)
			(layers "B.Cu" "B.Mask" "B.Paste")
			(net "P1V05_PCH_STBY_VCCA_PLL0")
		)
		(pad "2" smd rect
			(at 0 0.889 180)
			(size 0.508 0.508)
			(layers "B.Cu" "B.Mask" "B.Paste")
			(net "GND")
		)
		(zone
			(layer "B.Cu")
			(hatch none 0.5)
			(connect_pads
				(clearance 0)
			)
			(min_thickness 0.25)
			(keepout
				(tracks allowed)
				(vias not_allowed)
				(pads allowed)
				(copperpour not_allowed)
				(footprints allowed)
			)
			(placement
				(enabled no)
				(sheetname "")
			)
			(fill
				(thermal_gap 0.5)
				(thermal_bridge_width 0.5)
				(island_removal_mode 0)
			)
			(polygon
				(pts
					(xy 375.666 -134.5565) (xy 375.158 -134.5565) (xy 375.158 -134.1755) (xy 375.666 -134.1755)
				)
			)
		)
		(zone
			(layer "B.Cu")
			(hatch none 0.5)
			(connect_pads
				(clearance 0)
			)
			(min_thickness 0.25)
			(keepout
				(tracks not_allowed)
				(vias allowed)
				(pads allowed)
				(copperpour not_allowed)
				(footprints allowed)
			)
			(placement
				(enabled no)
				(sheetname "")
			)
			(fill
				(thermal_gap 0.5)
				(thermal_bridge_width 0.5)
				(island_removal_mode 0)
			)
			(polygon
				(pts
					(xy 375.666 -134.1755) (xy 375.158 -134.1755) (xy 375.158 -134.5565) (xy 375.666 -134.5565)
				)
			)
		)
	)
	(footprint ""
		(layer "B.Cu")
		(at 341.666068 -77.694536)
		(property "Reference" "C3P14"
			(at 0 0 0)
			(layer "B.SilkS")
			(hide yes)
			(effects
				(font
					(size 1.27 1.27)
				)
				(justify mirror)
			)
		)
		(property "Value" ""
			(at 0 0 0)
			(layer "B.Fab")
			(effects
				(font
					(size 1.27 1.27)
				)
				(justify mirror)
			)
		)
		(duplicate_pad_numbers_are_jumpers no)
		(fp_poly
			(pts
				(xy -0.3048 -0.1016) (xy -0.3048 0.9906) (xy 0.3048 0.9906) (xy 0.3048 -0.1016)
			)
			(stroke
				(width 0)
				(type default)
			)
			(fill no)
			(layer "B.CrtYd")
		)
		(fp_line
			(start -0.3048 -0.1016)
			(end 0.3048 -0.1016)
			(stroke
				(width 0.1)
				(type default)
			)
			(layer "B.Fab")
		)
		(fp_line
			(start -0.3048 0.9906)
			(end -0.3048 -0.1016)
			(stroke
				(width 0.1)
				(type default)
			)
			(layer "B.Fab")
		)
		(fp_line
			(start 0.3048 -0.1016)
			(end 0.3048 0.9906)
			(stroke
				(width 0.1)
				(type default)
			)
			(layer "B.Fab")
		)
		(fp_line
			(start 0.3048 0.9906)
			(end -0.3048 0.9906)
			(stroke
				(width 0.1)
				(type default)
			)
			(layer "B.Fab")
		)
		(pad "1" smd rect
			(at 0 0 180)
			(size 0.508 0.508)
			(layers "B.Cu" "B.Mask" "B.Paste")
			(net "P3E_CPU0_PE1_SS_TXP<1>")
		)
		(pad "2" smd rect
			(at 0 0.889 180)
			(size 0.508 0.508)
			(layers "B.Cu" "B.Mask" "B.Paste")
			(net "P3E_CPU0_PE1_SS_C_TXP<1>")
		)
		(zone
			(layer "B.Cu")
			(hatch none 0.5)
			(connect_pads
				(clearance 0)
			)
			(min_thickness 0.25)
			(keepout
				(tracks allowed)
				(vias not_allowed)
				(pads allowed)
				(copperpour not_allowed)
				(footprints allowed)
			)
			(placement
				(enabled no)
				(sheetname "")
			)
			(fill
				(thermal_gap 0.5)
				(thermal_bridge_width 0.5)
				(island_removal_mode 0)
			)
			(polygon
				(pts
					(xy 341.920068 -77.440536) (xy 341.412068 -77.440536) (xy 341.412068 -77.059536) (xy 341.920068 -77.059536)
				)
			)
		)
		(zone
			(layer "B.Cu")
			(hatch none 0.5)
			(connect_pads
				(clearance 0)
			)
			(min_thickness 0.25)
			(keepout
				(tracks not_allowed)
				(vias allowed)
				(pads allowed)
				(copperpour not_allowed)
				(footprints allowed)
			)
			(placement
				(enabled no)
				(sheetname "")
			)
			(fill
				(thermal_gap 0.5)
				(thermal_bridge_width 0.5)
				(island_removal_mode 0)
			)
			(polygon
				(pts
					(xy 341.920068 -77.059536) (xy 341.412068 -77.059536) (xy 341.412068 -77.440536) (xy 341.920068 -77.440536)
				)
			)
		)
	)
)
